# BASEBOARD_FAB2 (Tioga Pass) — schematic netlist excerpt (pin names and nets, part order shuffled) for the footprints in the layout excerpt that follows; sources: Cadence DE-HDL packaged netlist, KiCad conversion of Wiwynn_Tioga_Pass_MB.brd

R8D5  RES  1.00K 1% EMPTY  pkg 0402  page 125 : A = PU_ADR_TIMER_HOLD_OFF_N ; B = GND
R3B4  RES  100.0 1% CHIP  pkg 0402  page 55 : A = SVID_DIO0_CPU1_R ; B = PVCCIO_CPU1

U7D1  74CBTLV1G125  IC  pkg SMLF  page 118
  OE_N  = PWRGD_PVCCIO_CPU0
  A  = XDP_PCH_PWR_DEBUG_N
  B  = XDP_CPU_PWR_DEBUG_N

(kicad_pcb
	(version 20260206)
	(generator "pcbnew")
	(generator_version "10.0")
	(general
		(thickness 1.6)
		(legacy_teardrops no)
	)
	(paper "A4")
	(title_block
		(title "Wiwynn_Tioga_Pass_MB.brd")
		(comment 1 "Tioga Pass / footprints 861-863 of 4770")
	)
	(layers
		(0 "F.Cu" signal "TOP")
		(4 "In1.Cu" signal "L2GND")
		(6 "In2.Cu" signal "L3")
		(8 "In3.Cu" signal "L4GND")
		(10 "In4.Cu" signal "L5")
		(12 "In5.Cu" signal "L6GND")
		(14 "In6.Cu" signal "L7VCC")
		(16 "In7.Cu" signal "L8VCC")
		(18 "In8.Cu" signal "L9GND")
		(20 "In9.Cu" signal "L10")
		(22 "In10.Cu" signal "L11GND")
		(24 "In11.Cu" signal "L12")
		(26 "In12.Cu" signal "L13GND")
		(2 "B.Cu" signal "BOTTOM")
		(9 "F.Adhes" user "F.Adhesive")
		(11 "B.Adhes" user "B.Adhesive")
		(13 "F.Paste" user "Package Geometry/Pastemask Top")
		(15 "B.Paste" user "Package Geometry/Pastemask Bottom")
		(5 "F.SilkS" user "Ref Des/Silkscreen Top")
		(7 "B.SilkS" user "Ref Des/Silkscreen Bottom")
		(1 "F.Mask" user "Board Geometry/Soldermask Top")
		(3 "B.Mask" user "Board Geometry/Soldermask Bottom")
		(17 "Dwgs.User" user "User.Drawings")
		(19 "Cmts.User" user "User.Comments")
		(21 "Eco1.User" user "User.Eco1")
		(23 "Eco2.User" user "User.Eco2")
		(25 "Edge.Cuts" user "Board Geometry/Outline")
		(27 "Margin" user)
		(31 "F.CrtYd" user "Package Geometry/Place Bound Top")
		(29 "B.CrtYd" user "Package Geometry/Place Bound Bottom")
		(35 "F.Fab" user "Ref Des/Assembly Top")
		(33 "B.Fab" user "Ref Des/Assembly Bottom")
	)
	(footprint ""
		(layer "F.Cu")
		(at 391.403078 -86.569042)
		(property "Reference" "R8D5"
			(at 0 0 0)
			(layer "F.SilkS")
			(hide yes)
			(effects
				(font
					(size 1.27 1.27)
				)
			)
		)
		(property "Value" ""
			(at 0 0 0)
			(layer "F.Fab")
			(effects
				(font
					(size 1.27 1.27)
				)
			)
		)
		(duplicate_pad_numbers_are_jumpers no)
		(fp_poly
			(pts
				(xy -0.2794 -0.1016) (xy 0.2794 -0.1016) (xy 0.2794 0.9906) (xy -0.2794 0.9906)
			)
			(stroke
				(width 0)
				(type default)
			)
			(fill no)
			(layer "F.CrtYd")
		)
		(fp_line
			(start -0.2794 -0.1016)
			(end -0.2794 0.9906)
			(stroke
				(width 0.1)
				(type default)
			)
			(layer "F.Fab")
		)
		(fp_line
			(start -0.2794 0.9906)
			(end 0.2794 0.9906)
			(stroke
				(width 0.1)
				(type default)
			)
			(layer "F.Fab")
		)
		(fp_line
			(start 0.2794 -0.1016)
			(end -0.2794 -0.1016)
			(stroke
				(width 0.1)
				(type default)
			)
			(layer "F.Fab")
		)
		(fp_line
			(start 0.2794 0.9906)
			(end 0.2794 -0.1016)
			(stroke
				(width 0.1)
				(type default)
			)
			(layer "F.Fab")
		)
		(pad "1" smd rect
			(at 0 0)
			(size 0.508 0.508)
			(layers "F.Cu" "F.Mask" "F.Paste")
			(net "PU_ADR_TIMER_HOLD_OFF_N")
		)
		(pad "2" smd rect
			(at 0 0.889)
			(size 0.508 0.508)
			(layers "F.Cu" "F.Mask" "F.Paste")
			(net "GND")
		)
		(zone
			(layer "F.Cu")
			(hatch none 0.5)
			(connect_pads
				(clearance 0)
			)
			(min_thickness 0.25)
			(keepout
				(tracks allowed)
				(vias not_allowed)
				(pads allowed)
				(copperpour not_allowed)
				(footprints allowed)
			)
			(placement
				(enabled no)
				(sheetname "")
			)
			(fill
				(thermal_gap 0.5)
				(thermal_bridge_width 0.5)
				(island_removal_mode 0)
			)
			(polygon
				(pts
					(xy 391.149078 -86.315042) (xy 391.657078 -86.315042) (xy 391.657078 -85.934042) (xy 391.149078 -85.934042)
				)
			)
		)
		(zone
			(layer "F.Cu")
			(hatch none 0.5)
			(connect_pads
				(clearance 0)
			)
			(min_thickness 0.25)
			(keepout
				(tracks not_allowed)
				(vias allowed)
				(pads allowed)
				(copperpour not_allowed)
				(footprints allowed)
			)
			(placement
				(enabled no)
				(sheetname "")
			)
			(fill
				(thermal_gap 0.5)
				(thermal_bridge_width 0.5)
				(island_removal_mode 0)
			)
			(polygon
				(pts
					(xy 391.149078 -85.934042) (xy 391.657078 -85.934042) (xy 391.657078 -86.315042) (xy 391.149078 -86.315042)
				)
			)
		)
	)
	(footprint ""
		(layer "F.Cu")
		(at 369.2652 -92.1766 180)
		(property "Reference" "U7D1"
			(at 0.28194 -1.71323 180)
			(unlocked yes)
			(layer "F.SilkS")
			(effects
				(font
					(size 0.7874 0.5842)
					(thickness 0.1524)
				)
				(justify left)
			)
		)
		(property "Value" ""
			(at 0 0 180)
			(layer "F.Fab")
			(effects
				(font
					(size 1.27 1.27)
				)
			)
		)
		(duplicate_pad_numbers_are_jumpers no)
		(fp_circle
			(center -0.4699 -0.8382)
			(end -0.5969 -0.8382)
			(stroke
				(width 0.254)
				(type default)
			)
			(fill no)
			(layer "F.SilkS")
		)
		(fp_poly
			(pts
				(xy 0.21463 -0.450088) (xy 1.56337 -0.450088) (xy 1.56337 1.75006) (xy 0.21463 1.75006)
			)
			(stroke
				(width 0)
				(type default)
			)
			(fill no)
			(layer "F.CrtYd")
		)
		(fp_line
			(start 1.56337 1.75006)
			(end 0.21463 1.75006)
			(stroke
				(width 0.1)
				(type default)
			)
			(layer "F.Fab")
		)
		(fp_line
			(start 1.56337 -0.450088)
			(end 1.56337 1.75006)
			(stroke
				(width 0.1)
				(type default)
			)
			(layer "F.Fab")
		)
		(fp_line
			(start 0.21463 1.75006)
			(end 0.21463 -0.450088)
			(stroke
				(width 0.1)
				(type default)
			)
			(layer "F.Fab")
		)
		(fp_line
			(start 0.21463 -0.450088)
			(end 1.56337 -0.450088)
			(stroke
				(width 0.1)
				(type default)
			)
			(layer "F.Fab")
		)
		(fp_circle
			(center -0.4699 -0.8382)
			(end -0.5969 -0.8382)
			(stroke
				(width 0.254)
				(type default)
			)
			(fill no)
			(layer "F.Fab")
		)
		(pad "1" smd rect
			(at 0 0 180)
			(size 1.016 0.381)
			(layers "F.Cu" "F.Mask" "F.Paste")
			(net "PWRGD_PVCCIO_CPU0")
		)
		(pad "2" smd rect
			(at 0 0.649986 180)
			(size 1.016 0.381)
			(layers "F.Cu" "F.Mask" "F.Paste")
			(net "XDP_PCH_PWR_DEBUG_N")
		)
		(pad "3" smd rect
			(at 0 1.299972 180)
			(size 1.016 0.381)
			(layers "F.Cu" "F.Mask" "F.Paste")
			(net "GND")
		)
		(pad "4" smd rect
			(at 1.778 1.299972 180)
			(size 1.016 0.381)
			(layers "F.Cu" "F.Mask" "F.Paste")
			(net "XDP_CPU_PWR_DEBUG_N")
		)
		(pad "5" smd rect
			(at 1.778 0 180)
			(size 1.016 0.381)
			(layers "F.Cu" "F.Mask" "F.Paste")
			(net "P3V3_STBY")
		)
	)
	(footprint ""
		(layer "F.Cu")
		(at 157.988 -119.166386 90)
		(property "Reference" "R3B4"
			(at 0 0 90)
			(layer "F.SilkS")
			(hide yes)
			(effects
				(font
					(size 1.27 1.27)
				)
			)
		)
		(property "Value" ""
			(at 0 0 90)
			(layer "F.Fab")
			(effects
				(font
					(size 1.27 1.27)
				)
			)
		)
		(duplicate_pad_numbers_are_jumpers no)
		(fp_poly
			(pts
				(xy -0.2794 -0.1016) (xy 0.2794 -0.1016) (xy 0.2794 0.9906) (xy -0.2794 0.9906)
			)
			(stroke
				(width 0)
				(type default)
			)
			(fill no)
			(layer "F.CrtYd")
		)
		(fp_line
			(start 0.2794 -0.1016)
			(end -0.2794 -0.1016)
			(stroke
				(width 0.1)
				(type default)
			)
			(layer "F.Fab")
		)
		(fp_line
			(start -0.2794 -0.1016)
			(end -0.2794 0.9906)
			(stroke
				(width 0.1)
				(type default)
			)
			(layer "F.Fab")
		)
		(fp_line
			(start 0.2794 0.9906)
			(end 0.2794 -0.1016)
			(stroke
				(width 0.1)
				(type default)
			)
			(layer "F.Fab")
		)
		(fp_line
			(start -0.2794 0.9906)
			(end 0.2794 0.9906)
			(stroke
				(width 0.1)
				(type default)
			)
			(layer "F.Fab")
		)
		(pad "1" smd rect
			(at 0 0 90)
			(size 0.508 0.508)
			(layers "F.Cu" "F.Mask" "F.Paste")
			(net "SVID_DIO0_CPU1_R")
		)
		(pad "2" smd rect
			(at 0 0.889 90)
			(size 0.508 0.508)
			(layers "F.Cu" "F.Mask" "F.Paste")
			(net "PVCCIO_CPU1")
		)
		(zone
			(layer "F.Cu")
			(hatch none 0.5)
			(connect_pads
				(clearance 0)
			)
			(min_thickness 0.25)
			(keepout
				(tracks allowed)
				(vias not_allowed)
				(pads allowed)
				(copperpour not_allowed)
				(footprints allowed)
			)
			(placement
				(enabled no)
				(sheetname "")
			)
			(fill
				(thermal_gap 0.5)
				(thermal_bridge_width 0.5)
				(island_removal_mode 0)
			)
			(polygon
				(pts
					(xy 158.242 -118.912386) (xy 158.242 -119.420386) (xy 158.623 -119.420386) (xy 158.623 -118.912386)
				)
			)
		)
		(zone
			(layer "F.Cu")
			(hatch none 0.5)
			(connect_pads
				(clearance 0)
			)
			(min_thickness 0.25)
			(keepout
				(tracks not_allowed)
				(vias allowed)
				(pads allowed)
				(copperpour not_allowed)
				(footprints allowed)
			)
			(placement
				(enabled no)
				(sheetname "")
			)
			(fill
				(thermal_gap 0.5)
				(thermal_bridge_width 0.5)
				(island_removal_mode 0)
			)
			(polygon
				(pts
					(xy 158.623 -118.912386) (xy 158.623 -119.420386) (xy 158.242 -119.420386) (xy 158.242 -118.912386)
				)
			)
		)
	)
)
